#ISCELL
  mstr_misc dns *
  *
#ISCELL
  pure_quanta quanta_title_block_c *
  *
#CELL
  pure_quanta 74lvc2g08dp *
  page170_i1
#ISCELL
  standard offpage *
  page170_i10
#CELL
  pure_quanta 74lvc2g08dp *
  page170_i11
#CELL
  pure_quanta 74lvc2g08dp *
  page170_i12
#CELL
  pure_quanta 74lvc2g08dp *
  page170_i13
#CELL
  pure_quanta 74lvc2g08dp *
  page170_i14
#CELL
  pure_quanta nc7sb3157 *
  page170_i15
#CELL
  pure_quanta nc7sb3157 *
  page170_i16
#CELL
  pure_quanta nc7sb3157 *
  page170_i17
#CELL
  pure_quanta nc7sb3157 *
  page170_i18
#ISCELL
  logical_power universal_gnd *
  page170_i19
#CELL
  pure_quanta 74lvc2g08dp *
  page170_i2
#ISCELL
  logical_power universal_power *
  page170_i20
#CELL
  pure_quanta q_cap *
  page170_i21
#CELL
  pure_quanta q_cap *
  page170_i22
#ISCELL
  logical_power universal_power *
  page170_i23
#ISCELL
  logical_power universal_gnd *
  page170_i24
#ISCELL
  logical_power universal_gnd *
  page170_i25
#ISCELL
  logical_power universal_gnd *
  page170_i26
#CELL
  pure_quanta q_cap *
  page170_i27
#ISCELL
  logical_power universal_gnd *
  page170_i28
#ISCELL
  logical_power universal_power *
  page170_i29
#ISCELL
  standard offpage *
  page170_i3
#ISCELL
  logical_power universal_power *
  page170_i30
#CELL
  pure_quanta q_cap *
  page170_i31
#ISCELL
  logical_power universal_gnd *
  page170_i32
#ISCELL
  logical_power universal_power *
  page170_i33
#CELL
  pure_quanta q_cap *
  page170_i34
#ISCELL
  logical_power universal_gnd *
  page170_i35
#ISCELL
  logical_power universal_gnd *
  page170_i36
#CELL
  pure_quanta q_cap *
  page170_i37
#ISCELL
  logical_power universal_power *
  page170_i38
#ISCELL
  logical_power universal_gnd *
  page170_i39
#ISCELL
  standard offpage *
  page170_i4
#ISCELL
  logical_power universal_power *
  page170_i40
#CELL
  pure_quanta q_cap *
  page170_i41
#ISCELL
  logical_power universal_gnd *
  page170_i42
#CELL
  pure_quanta q_res *
  page170_i44
#CELL
  pure_quanta q_res *
  page170_i45
#CELL
  pure_quanta q_res *
  page170_i46
#CELL
  pure_quanta q_res *
  page170_i47
#ISCELL
  standard offpage *
  page170_i48
#ISCELL
  standard offpage *
  page170_i49
#ISCELL
  standard offpage *
  page170_i5
#CELL
  pure_quanta q_res *
  page170_i50
#ISCELL
  standard offpage *
  page170_i51
#CELL
  pure_quanta q_res *
  page170_i52
#ISCELL
  standard offpage *
  page170_i53
#ISCELL
  standard offpage *
  page170_i54
#ISCELL
  standard offpage *
  page170_i56
#ISCELL
  standard offpage *
  page170_i58
#ISCELL
  standard offpage *
  page170_i59
#ISCELL
  standard offpage *
  page170_i6
#ISCELL
  logical_power universal_gnd *
  page170_i60
#ISCELL
  logical_power universal_gnd *
  page170_i61
#ISCELL
  logical_power universal_gnd *
  page170_i62
#ISCELL
  logical_power universal_gnd *
  page170_i63
#ISCELL
  standard offpage *
  page170_i7
#ISCELL
  standard offpage *
  page170_i8
#ISCELL
  standard offpage *
  page170_i9
